# T6G (Grand Teton) — schematic netlist excerpt (pin names and nets, part order shuffled) for the footprints in the layout excerpt that follows; sources: Cadence DE-HDL packaged netlist, KiCad conversion of 04192023_DAF0TMB3IC0_F0TG_MB_C_brd_V02_OCP.brd

C6106  Q_CAP  1PF 50V 0.05P COG  pkg C0402  page 179 : A = P1V2_CPU0_USB2_DVDD12 ; B = GND
C498  Q_CAP  0.1UF 10V 10% X7S  pkg C0201  page 356 : A = P0V9_CPU1_RT3_2A ; B = GND
PR325  Q_RES  0 5% CHIP  pkg 0402LF  page 194 : A = PVDDCR_CPU0_P0_VOS2 ; B = PVDDCR_CPU0_P0

(kicad_pcb
	(version 20260206)
	(generator "pcbnew")
	(generator_version "10.0")
	(general
		(thickness 1.6)
		(legacy_teardrops no)
	)
	(paper "A4")
	(title_block
		(title "04192023_DAF0TMB3IC0_F0TG_MB_C_brd_V02_OCP.brd")
		(comment 1 "Grand Teton / footprints 7082-7084 of 8354")
	)
	(layers
		(0 "F.Cu" signal "TOP")
		(4 "In1.Cu" signal "GND")
		(6 "In2.Cu" signal "IN1")
		(8 "In3.Cu" signal "GND1")
		(10 "In4.Cu" signal "IN2")
		(12 "In5.Cu" signal "GND2")
		(14 "In6.Cu" signal "IN3")
		(16 "In7.Cu" signal "GND3")
		(18 "In8.Cu" signal "VCC")
		(20 "In9.Cu" signal "VCC1")
		(22 "In10.Cu" signal "GND4")
		(24 "In11.Cu" signal "IN4")
		(26 "In12.Cu" signal "GND5")
		(28 "In13.Cu" signal "IN5")
		(30 "In14.Cu" signal "GND6")
		(32 "In15.Cu" signal "IN6")
		(34 "In16.Cu" signal "GND7")
		(2 "B.Cu" signal "BOTTOM")
		(9 "F.Adhes" user "F.Adhesive")
		(11 "B.Adhes" user "B.Adhesive")
		(13 "F.Paste" user "Package Geometry/Pastemask Top")
		(15 "B.Paste" user "Package Geometry/Pastemask Bottom")
		(5 "F.SilkS" user "Ref Des/Silkscreen Top")
		(7 "B.SilkS" user "Ref Des/Silkscreen Bottom")
		(1 "F.Mask" user "Board Geometry/Soldermask Top")
		(3 "B.Mask" user "Board Geometry/Soldermask Bottom")
		(17 "Dwgs.User" user "User.Drawings")
		(19 "Cmts.User" user "User.Comments")
		(21 "Eco1.User" user "User.Eco1")
		(23 "Eco2.User" user "User.Eco2")
		(25 "Edge.Cuts" user "Board Geometry/Outline")
		(27 "Margin" user)
		(31 "F.CrtYd" user "Package Geometry/Place Bound Top")
		(29 "B.CrtYd" user "Package Geometry/Place Bound Bottom")
		(35 "F.Fab" user "Ref Des/Assembly Top")
		(33 "B.Fab" user "Ref Des/Assembly Bottom")
	)
	(footprint ""
		(layer "B.Cu")
		(at 113.841022 -26.03246)
		(property "Reference" "C6106"
			(at 0 0 0)
			(layer "B.SilkS")
			(hide yes)
			(effects
				(font
					(size 1.27 1.27)
				)
				(justify mirror)
			)
		)
		(property "Value" ""
			(at 0 0 0)
			(layer "B.Fab")
			(effects
				(font
					(size 1.27 1.27)
				)
				(justify mirror)
			)
		)
		(duplicate_pad_numbers_are_jumpers no)
		(fp_line
			(start -0.7874 -0.4064)
			(end -0.7874 0.4064)
			(stroke
				(width 0.1524)
				(type default)
			)
			(layer "B.SilkS")
		)
		(fp_line
			(start -0.7874 0.4064)
			(end 0.7874 0.4064)
			(stroke
				(width 0.1524)
				(type default)
			)
			(layer "B.SilkS")
		)
		(fp_line
			(start 0.7874 -0.4064)
			(end -0.7874 -0.4064)
			(stroke
				(width 0.1524)
				(type default)
			)
			(layer "B.SilkS")
		)
		(fp_line
			(start 0.7874 0.4064)
			(end 0.7874 -0.4064)
			(stroke
				(width 0.1524)
				(type default)
			)
			(layer "B.SilkS")
		)
		(fp_line
			(start -0.67945 -0.3048)
			(end -0.67945 0.3048)
			(stroke
				(width 0.1)
				(type default)
			)
			(layer "B.Fab")
		)
		(fp_line
			(start -0.67945 0.3048)
			(end -0.120396 0.3048)
			(stroke
				(width 0.1)
				(type default)
			)
			(layer "B.Fab")
		)
		(fp_line
			(start -0.12065 -0.3048)
			(end -0.67945 -0.3048)
			(stroke
				(width 0.1)
				(type default)
			)
			(layer "B.Fab")
		)
		(fp_line
			(start -0.12065 -0.2794)
			(end -0.12065 -0.3048)
			(stroke
				(width 0.1)
				(type default)
			)
			(layer "B.Fab")
		)
		(fp_line
			(start -0.120396 0.2794)
			(end 0.12065 0.2794)
			(stroke
				(width 0.1)
				(type default)
			)
			(layer "B.Fab")
		)
		(fp_line
			(start -0.120396 0.3048)
			(end -0.120396 0.2794)
			(stroke
				(width 0.1)
				(type default)
			)
			(layer "B.Fab")
		)
		(fp_line
			(start 0.12065 -0.305054)
			(end 0.12065 -0.2794)
			(stroke
				(width 0.1)
				(type default)
			)
			(layer "B.Fab")
		)
		(fp_line
			(start 0.12065 -0.2794)
			(end -0.12065 -0.2794)
			(stroke
				(width 0.1)
				(type default)
			)
			(layer "B.Fab")
		)
		(fp_line
			(start 0.12065 0.2794)
			(end 0.12065 0.3048)
			(stroke
				(width 0.1)
				(type default)
			)
			(layer "B.Fab")
		)
		(fp_line
			(start 0.12065 0.3048)
			(end 0.67945 0.3048)
			(stroke
				(width 0.1)
				(type default)
			)
			(layer "B.Fab")
		)
		(fp_line
			(start 0.67945 -0.305054)
			(end 0.12065 -0.305054)
			(stroke
				(width 0.1)
				(type default)
			)
			(layer "B.Fab")
		)
		(fp_line
			(start 0.67945 0.3048)
			(end 0.67945 -0.305054)
			(stroke
				(width 0.1)
				(type default)
			)
			(layer "B.Fab")
		)
		(pad "1" smd circle
			(at 0.40005 0 180)
			(size 0 0)
			(layers "B.Cu" "B.Mask" "B.Paste")
			(net "P1V2_CPU0_USB2_DVDD12")
		)
		(pad "2" smd circle
			(at -0.40005 0 180)
			(size 0 0)
			(layers "B.Cu" "B.Mask" "B.Paste")
			(net "GND")
		)
	)
	(footprint ""
		(layer "B.Cu")
		(at 376.33656 -180.078634 90)
		(property "Reference" "PR325"
			(at 0 0 90)
			(layer "B.SilkS")
			(hide yes)
			(effects
				(font
					(size 1.27 1.27)
				)
				(justify mirror)
			)
		)
		(property "Value" ""
			(at 0 0 90)
			(layer "B.Fab")
			(effects
				(font
					(size 1.27 1.27)
				)
				(justify mirror)
			)
		)
		(duplicate_pad_numbers_are_jumpers no)
		(fp_line
			(start 0.7874 -0.4064)
			(end -0.7874 -0.4064)
			(stroke
				(width 0.1524)
				(type default)
			)
			(layer "B.SilkS")
		)
		(fp_line
			(start -0.7874 -0.4064)
			(end -0.7874 0.4064)
			(stroke
				(width 0.1524)
				(type default)
			)
			(layer "B.SilkS")
		)
		(fp_line
			(start 0.7874 0.4064)
			(end 0.7874 -0.4064)
			(stroke
				(width 0.1524)
				(type default)
			)
			(layer "B.SilkS")
		)
		(fp_line
			(start -0.7874 0.4064)
			(end 0.7874 0.4064)
			(stroke
				(width 0.1524)
				(type default)
			)
			(layer "B.SilkS")
		)
		(fp_line
			(start 0.67945 -0.305054)
			(end 0.12065 -0.305054)
			(stroke
				(width 0.1)
				(type default)
			)
			(layer "B.Fab")
		)
		(fp_line
			(start 0.12065 -0.305054)
			(end 0.12065 -0.2794)
			(stroke
				(width 0.1)
				(type default)
			)
			(layer "B.Fab")
		)
		(fp_line
			(start -0.12065 -0.3048)
			(end -0.67945 -0.3048)
			(stroke
				(width 0.1)
				(type default)
			)
			(layer "B.Fab")
		)
		(fp_line
			(start -0.67945 -0.3048)
			(end -0.67945 0.3048)
			(stroke
				(width 0.1)
				(type default)
			)
			(layer "B.Fab")
		)
		(fp_line
			(start 0.12065 -0.2794)
			(end -0.12065 -0.2794)
			(stroke
				(width 0.1)
				(type default)
			)
			(layer "B.Fab")
		)
		(fp_line
			(start -0.12065 -0.2794)
			(end -0.12065 -0.3048)
			(stroke
				(width 0.1)
				(type default)
			)
			(layer "B.Fab")
		)
		(fp_line
			(start 0.12065 0.2794)
			(end 0.12065 0.3048)
			(stroke
				(width 0.1)
				(type default)
			)
			(layer "B.Fab")
		)
		(fp_line
			(start -0.120396 0.2794)
			(end 0.12065 0.2794)
			(stroke
				(width 0.1)
				(type default)
			)
			(layer "B.Fab")
		)
		(fp_line
			(start 0.67945 0.3048)
			(end 0.67945 -0.305054)
			(stroke
				(width 0.1)
				(type default)
			)
			(layer "B.Fab")
		)
		(fp_line
			(start 0.12065 0.3048)
			(end 0.67945 0.3048)
			(stroke
				(width 0.1)
				(type default)
			)
			(layer "B.Fab")
		)
		(fp_line
			(start -0.120396 0.3048)
			(end -0.120396 0.2794)
			(stroke
				(width 0.1)
				(type default)
			)
			(layer "B.Fab")
		)
		(fp_line
			(start -0.67945 0.3048)
			(end -0.120396 0.3048)
			(stroke
				(width 0.1)
				(type default)
			)
			(layer "B.Fab")
		)
		(pad "1" smd circle
			(at 0.40005 0 270)
			(size 0 0)
			(layers "B.Cu" "B.Mask" "B.Paste")
			(net "PVDDCR_CPU0_P0_VOS2")
		)
		(pad "2" smd circle
			(at -0.40005 0 270)
			(size 0 0)
			(layers "B.Cu" "B.Mask" "B.Paste")
			(net "PVDDCR_CPU0_P0")
		)
	)
	(footprint ""
		(layer "B.Cu")
		(at 112.521238 -388.296912)
		(property "Reference" "C498"
			(at 0 0 0)
			(layer "B.SilkS")
			(hide yes)
			(effects
				(font
					(size 1.27 1.27)
				)
				(justify mirror)
			)
		)
		(property "Value" ""
			(at 0 0 0)
			(layer "B.Fab")
			(effects
				(font
					(size 1.27 1.27)
				)
				(justify mirror)
			)
		)
		(duplicate_pad_numbers_are_jumpers no)
		(fp_line
			(start -0.299974 -0.150114)
			(end -0.299974 0.150114)
			(stroke
				(width 0.1)
				(type default)
			)
			(layer "B.Fab")
		)
		(fp_line
			(start -0.299974 0.150114)
			(end 0.299974 0.150114)
			(stroke
				(width 0.1)
				(type default)
			)
			(layer "B.Fab")
		)
		(fp_line
			(start 0.299974 -0.150114)
			(end -0.299974 -0.150114)
			(stroke
				(width 0.1)
				(type default)
			)
			(layer "B.Fab")
		)
		(fp_line
			(start 0.299974 0.150114)
			(end 0.299974 -0.150114)
			(stroke
				(width 0.1)
				(type default)
			)
			(layer "B.Fab")
		)
		(pad "1" smd rect
			(at 0.2667 0 180)
			(size 0.3048 0.381)
			(layers "B.Cu" "B.Mask" "B.Paste")
			(net "P0V9_CPU1_RT3_2A")
		)
		(pad "2" smd rect
			(at -0.2667 0 180)
			(size 0.3048 0.381)
			(layers "B.Cu" "B.Mask" "B.Paste")
			(net "GND")
		)
	)
)
